(kicad_pcb
	(version 20241229)
	(generator "pcbnew")
	(generator_version "9.0")
	(general
		(thickness 1.62)
		(legacy_teardrops no)
	)
	(paper "A4")
	(title_block
		(title "OCuLink to 10GbE adapter")
		(date "2026-02-23")
		(rev "1.1.0")
		(company "Antmicro Ltd")
		(comment 1 "www.antmicro.com")
		(comment 9 "footprints 236-242 of 510")
	)
	(layers
		(0 "F.Cu" signal)
		(4 "In1.Cu" signal)
		(6 "In2.Cu" signal)
		(8 "In3.Cu" signal)
		(10 "In4.Cu" signal)
		(12 "In5.Cu" signal)
		(14 "In6.Cu" signal)
		(2 "B.Cu" signal)
		(9 "F.Adhes" user "F.Adhesive")
		(11 "B.Adhes" user "B.Adhesive")
		(13 "F.Paste" user)
		(15 "B.Paste" user)
		(5 "F.SilkS" user "F.Silkscreen")
		(7 "B.SilkS" user "B.Silkscreen")
		(1 "F.Mask" user)
		(3 "B.Mask" user)
		(17 "Dwgs.User" user "User.Drawings")
		(19 "Cmts.User" user "User.Comments")
		(21 "Eco1.User" user "User.Eco1")
		(23 "Eco2.User" user "User.Eco2")
		(25 "Edge.Cuts" user)
		(27 "Margin" user)
		(31 "F.CrtYd" user "F.Courtyard")
		(29 "B.CrtYd" user "B.Courtyard")
		(35 "F.Fab" user)
		(33 "B.Fab" user)
	)
	(footprint "antmicro-footprints:C_0603_1608Metric_EIA"
		(layer "F.Cu")
		(at 66.7 87.699999 180)
		(descr "Capacitor SMD 0603, IPC-7351 Density Level A")
		(tags "Capacitor 0603")
		(property "Reference" "C126"
			(at 0.99 0.539999 0)
			(layer "F.SilkS")
			(effects
				(font
					(size 0.7 0.7)
					(thickness 0.15)
				)
				(justify right top)
			)
		)
		(property "Value" "C_22u_16V_0603"
			(at -1.42757 1.770288 0)
			(layer "F.Fab")
			(hide yes)
			(effects
				(font
					(size 0.7 0.7)
					(thickness 0.15)
				)
				(justify right top)
			)
		)
		(property "Datasheet" "https://product.samsungsem.com/mlcc/CL10A226MO7JZN.do"
			(at 0 0 0)
			(layer "F.Fab")
			(hide yes)
			(effects
				(font
					(size 1.27 1.27)
					(thickness 0.15)
				)
			)
		)
		(property "Description" "SMD Multilayer Ceramic Capacitor"
			(at 0 0 0)
			(layer "F.Fab")
			(hide yes)
			(effects
				(font
					(size 1.27 1.27)
					(thickness 0.15)
				)
			)
		)
		(property "MPN" "CL10A226MO7JZNC"
			(at 0 0 180)
			(unlocked yes)
			(layer "F.Fab")
			(hide yes)
			(effects
				(font
					(size 1 1)
					(thickness 0.15)
				)
			)
		)
		(property "Manufacturer" "Samsung Electro-Mechanics"
			(at 0 0 180)
			(unlocked yes)
			(layer "F.Fab")
			(hide yes)
			(effects
				(font
					(size 1 1)
					(thickness 0.15)
				)
			)
		)
		(property "License" "Apache-2.0"
			(at 0 0 180)
			(unlocked yes)
			(layer "F.Fab")
			(hide yes)
			(effects
				(font
					(size 1 1)
					(thickness 0.15)
				)
			)
		)
		(property "Author" "Antmicro"
			(at 0 0 180)
			(unlocked yes)
			(layer "F.Fab")
			(hide yes)
			(effects
				(font
					(size 1 1)
					(thickness 0.15)
				)
			)
		)
		(property "Val" "22u"
			(at 0 0 180)
			(unlocked yes)
			(layer "F.Fab")
			(hide yes)
			(effects
				(font
					(size 1 1)
					(thickness 0.15)
				)
			)
		)
		(property "Voltage" "16V"
			(at 0 0 180)
			(unlocked yes)
			(layer "F.Fab")
			(hide yes)
			(effects
				(font
					(size 1 1)
					(thickness 0.15)
				)
			)
		)
		(property "Dielectric" ""
			(at 0 0 180)
			(unlocked yes)
			(layer "F.Fab")
			(hide yes)
			(effects
				(font
					(size 1 1)
					(thickness 0.15)
				)
			)
		)
		(sheetname "/X710-AT2 power/")
		(sheetfile "x710-at2-power.kicad_sch")
		(attr smd)
		(fp_line
			(start -0.15 0.55)
			(end 0.15 0.55)
			(stroke
				(width 0.15)
				(type solid)
			)
			(layer "F.SilkS")
		)
		(fp_line
			(start -0.15 -0.55)
			(end 0.15 -0.55)
			(stroke
				(width 0.15)
				(type solid)
			)
			(layer "F.SilkS")
		)
		(fp_rect
			(start -1.25 -0.65)
			(end 1.25 0.65)
			(stroke
				(width 0.05)
				(type solid)
			)
			(fill no)
			(layer "F.CrtYd")
		)
		(fp_rect
			(start -0.8 -0.45)
			(end 0.8 0.45)
			(stroke
				(width 0.15)
				(type solid)
			)
			(fill no)
			(layer "F.Fab")
		)
		(pad "1" smd roundrect
			(at -0.7 0 180)
			(size 0.8 1.1)
			(layers "F.Cu" "F.Mask" "F.Paste")
			(roundrect_rratio 0.2)
			(net 28 "GND")
			(pintype "passive")
		)
		(pad "2" smd roundrect
			(at 0.7 0 180)
			(size 0.8 1.1)
			(layers "F.Cu" "F.Mask" "F.Paste")
			(roundrect_rratio 0.2)
			(net 9 "VCCD")
			(pintype "passive")
		)
	)
	(footprint "antmicro-footprints:FB_0603_1608Metric"
		(layer "F.Cu")
		(at 67.25 109.15)
		(property "Reference" "FB5"
			(at -2.56 -0.53 0)
			(layer "F.SilkS")
			(effects
				(font
					(size 0.7 0.7)
					(thickness 0.15)
				)
				(justify left bottom)
			)
		)
		(property "Value" "FB_33Z_3A_Murata-BLM18PG_0603"
			(at 0 1.5 0)
			(layer "F.Fab")
			(hide yes)
			(effects
				(font
					(size 0.7 0.7)
					(thickness 0.15)
				)
				(justify left bottom)
			)
		)
		(property "Datasheet" "https://www.murata.com/products/productdata/8796737273886/QNFA9101.pdf?1649080818000"
			(at 0 0 0)
			(layer "F.Fab")
			(hide yes)
			(effects
				(font
					(size 1.27 1.27)
					(thickness 0.15)
				)
			)
		)
		(property "Description" "Ferrite Bead, 0603 [1608 Metric], 33 ohm, 3 A, BLM18PG, 0.025 ohm, ± 25%, DC power line"
			(at 0 0 0)
			(layer "F.Fab")
			(hide yes)
			(effects
				(font
					(size 1.27 1.27)
					(thickness 0.15)
				)
			)
		)
		(property "Val" "33Z/3A"
			(at 0 0 0)
			(unlocked yes)
			(layer "F.Fab")
			(hide yes)
			(effects
				(font
					(size 1 1)
					(thickness 0.15)
				)
			)
		)
		(property "MPN" "BLM18PG330SH1D"
			(at 0 0 0)
			(unlocked yes)
			(layer "F.Fab")
			(hide yes)
			(effects
				(font
					(size 1 1)
					(thickness 0.15)
				)
			)
		)
		(property "Manufacturer" "Murata"
			(at 0 0 0)
			(unlocked yes)
			(layer "F.Fab")
			(hide yes)
			(effects
				(font
					(size 1 1)
					(thickness 0.15)
				)
			)
		)
		(property "Current" ""
			(at 0 0 0)
			(unlocked yes)
			(layer "F.Fab")
			(hide yes)
			(effects
				(font
					(size 1 1)
					(thickness 0.15)
				)
			)
		)
		(property "Author" "Antmicro"
			(at 0 0 0)
			(unlocked yes)
			(layer "F.Fab")
			(hide yes)
			(effects
				(font
					(size 1 1)
					(thickness 0.15)
				)
			)
		)
		(property "License" "Apache-2.0"
			(at 0 0 0)
			(unlocked yes)
			(layer "F.Fab")
			(hide yes)
			(effects
				(font
					(size 1 1)
					(thickness 0.15)
				)
			)
		)
		(sheetname "/X710-AT2 power/")
		(sheetfile "x710-at2-power.kicad_sch")
		(attr smd)
		(fp_line
			(start -0.15 -0.4)
			(end 0.15 -0.4)
			(stroke
				(width 0.15)
				(type solid)
			)
			(layer "F.SilkS")
		)
		(fp_line
			(start -0.15 0.4)
			(end 0.15 0.4)
			(stroke
				(width 0.15)
				(type solid)
			)
			(layer "F.SilkS")
		)
		(fp_rect
			(start -1.25 -0.65)
			(end 1.25 0.65)
			(stroke
				(width 0.05)
				(type solid)
			)
			(fill no)
			(layer "F.CrtYd")
		)
		(fp_line
			(start -0.803 0.406)
			(end -0.803 -0.408)
			(stroke
				(width 0.15)
				(type solid)
			)
			(layer "F.Fab")
		)
		(fp_line
			(start 0.8 -0.408)
			(end -0.803 -0.408)
			(stroke
				(width 0.15)
				(type solid)
			)
			(layer "F.Fab")
		)
		(fp_line
			(start 0.8 -0.408)
			(end 0.8 0.406)
			(stroke
				(width 0.15)
				(type solid)
			)
			(layer "F.Fab")
		)
		(fp_line
			(start 0.8 0.406)
			(end -0.803 0.406)
			(stroke
				(width 0.15)
				(type solid)
			)
			(layer "F.Fab")
		)
		(pad "1" smd roundrect
			(at -0.7 0)
			(size 0.8 1)
			(layers "F.Cu" "F.Mask" "F.Paste")
			(roundrect_rratio 0.2)
			(net 302 "+1V0")
			(pintype "passive")
		)
		(pad "2" smd roundrect
			(at 0.7 0)
			(size 0.8 1)
			(layers "F.Cu" "F.Mask" "F.Paste")
			(roundrect_rratio 0.2)
			(net 5 "P0_AVDDL")
			(pintype "passive")
		)
	)
	(footprint "antmicro-footprints:R_0402_1005Metric"
		(layer "F.Cu")
		(at 53.161 80.7 90)
		(descr "Resistor SMD 0402")
		(tags "resistor SMD 0402")
		(property "Reference" "R51"
			(at -1.07 1.239 90)
			(layer "F.SilkS")
			(effects
				(font
					(size 0.7 0.7)
					(thickness 0.15)
				)
				(justify left bottom)
			)
		)
		(property "Value" "R_3k3_0402"
			(at -1.011843 1.772046 90)
			(layer "F.Fab")
			(hide yes)
			(effects
				(font
					(size 0.7 0.7)
					(thickness 0.15)
				)
				(justify left bottom)
			)
		)
		(property "Datasheet" "https://www.bourns.com/docs/product-datasheets/cr.pdf"
			(at 0 0 90)
			(layer "F.Fab")
			(hide yes)
			(effects
				(font
					(size 1.27 1.27)
					(thickness 0.15)
				)
			)
		)
		(property "Description" "SMD Chip Resistor, 3.3 kohm, ± 1%, 63 mW, 0402 [1005 Metric], Thick Film, General Purpose"
			(at 0 0 90)
			(layer "F.Fab")
			(hide yes)
			(effects
				(font
					(size 1.27 1.27)
					(thickness 0.15)
				)
			)
		)
		(property "MPN" "CR0402-FX-3301GLF"
			(at 0 0 90)
			(unlocked yes)
			(layer "F.Fab")
			(hide yes)
			(effects
				(font
					(size 1 1)
					(thickness 0.15)
				)
			)
		)
		(property "Manufacturer" "Bourns"
			(at 0 0 90)
			(unlocked yes)
			(layer "F.Fab")
			(hide yes)
			(effects
				(font
					(size 1 1)
					(thickness 0.15)
				)
			)
		)
		(property "License" "Apache-2.0"
			(at 0 0 90)
			(unlocked yes)
			(layer "F.Fab")
			(hide yes)
			(effects
				(font
					(size 1 1)
					(thickness 0.15)
				)
			)
		)
		(property "Author" "Antmicro"
			(at 0 0 90)
			(unlocked yes)
			(layer "F.Fab")
			(hide yes)
			(effects
				(font
					(size 1 1)
					(thickness 0.15)
				)
			)
		)
		(property "Val" "3k3"
			(at 0 0 90)
			(unlocked yes)
			(layer "F.Fab")
			(hide yes)
			(effects
				(font
					(size 1 1)
					(thickness 0.15)
				)
			)
		)
		(property "Tolerance" "1%"
			(at 0 0 90)
			(unlocked yes)
			(layer "F.Fab")
			(hide yes)
			(effects
				(font
					(size 1 1)
					(thickness 0.15)
				)
			)
		)
		(sheetname "/X710-AT2 PCIe/")
		(sheetfile "x710-at2-pcie.kicad_sch")
		(attr smd)
		(fp_rect
			(start -0.925 -0.47)
			(end 0.925 0.47)
			(stroke
				(width 0.05)
				(type default)
			)
			(fill no)
			(layer "F.CrtYd")
		)
		(fp_rect
			(start -0.5 -0.25)
			(end 0.5 0.25)
			(stroke
				(width 0.15)
				(type solid)
			)
			(fill no)
			(layer "F.Fab")
		)
		(pad "1" smd roundrect
			(at -0.48 0 90)
			(size 0.59 0.64)
			(layers "F.Cu" "F.Mask" "F.Paste")
			(roundrect_rratio 0.25)
			(net 8 "/X710-AT2 PCIe/PCIe_JTAG.JTDO")
			(pintype "passive")
		)
		(pad "2" smd roundrect
			(at 0.48 0 90)
			(size 0.59 0.64)
			(layers "F.Cu" "F.Mask" "F.Paste")
			(roundrect_rratio 0.25)
			(net 7 "+3V3")
			(pintype "passive")
		)
	)
	(footprint "antmicro-footprints:TP_SMD_0.75mm"
		(layer "F.Cu")
		(at 79.55 65.443001)
		(property "Reference" "TP24"
			(at 0.35 -0.343001 90)
			(layer "F.SilkS")
			(effects
				(font
					(size 0.7 0.7)
					(thickness 0.15)
				)
				(justify left bottom)
			)
		)
		(property "Value" "TP_0.75mm_SMD"
			(at 0 1.2 0)
			(layer "F.Fab")
			(hide yes)
			(effects
				(font
					(size 0.7 0.7)
					(thickness 0.15)
				)
				(justify left bottom)
			)
		)
		(property "Description" "SMT test point"
			(at 0 0 0)
			(layer "F.Fab")
			(hide yes)
			(effects
				(font
					(size 1.27 1.27)
					(thickness 0.15)
				)
			)
		)
		(property "MPN" ""
			(at 0 0 0)
			(unlocked yes)
			(layer "F.Fab")
			(hide yes)
			(effects
				(font
					(size 1 1)
					(thickness 0.15)
				)
			)
		)
		(property "Manufacturer" ""
			(at 0 0 0)
			(unlocked yes)
			(layer "F.Fab")
			(hide yes)
			(effects
				(font
					(size 1 1)
					(thickness 0.15)
				)
			)
		)
		(property "Author" "Antmicro"
			(at 0 0 0)
			(unlocked yes)
			(layer "F.Fab")
			(hide yes)
			(effects
				(font
					(size 1 1)
					(thickness 0.15)
				)
			)
		)
		(property "License" "Apache-2.0"
			(at 0 0 0)
			(unlocked yes)
			(layer "F.Fab")
			(hide yes)
			(effects
				(font
					(size 1 1)
					(thickness 0.15)
				)
			)
		)
		(sheetname "/Power/")
		(sheetfile "power.kicad_sch")
		(attr exclude_from_pos_files exclude_from_bom)
		(fp_circle
			(center 0 0)
			(end 0.475 0)
			(stroke
				(width 0.05)
				(type default)
			)
			(fill no)
			(layer "F.CrtYd")
		)
		(pad "1" smd circle
			(at 0 0)
			(size 0.75 0.75)
			(layers "F.Cu" "F.Mask")
			(net 351 "/Power/+5V_USB")
			(pinfunction "1")
			(pintype "passive")
		)
	)
	(footprint "antmicro-footprints:R_0402_1005Metric"
		(layer "F.Cu")
		(at 116.95 106.55 180)
		(descr "Resistor SMD 0402")
		(tags "resistor SMD 0402")
		(property "Reference" "R181"
			(at 0.85 0.45 0)
			(layer "F.SilkS")
			(effects
				(font
					(size 0.7 0.7)
					(thickness 0.15)
				)
				(justify right top)
			)
		)
		(property "Value" "R_0R_0402"
			(at -1.011843 1.772046 0)
			(layer "F.Fab")
			(hide yes)
			(effects
				(font
					(size 0.7 0.7)
					(thickness 0.15)
				)
				(justify right top)
			)
		)
		(property "Datasheet" "https://industrial.panasonic.com/cdbs/www-data/pdf/RDA0000/AOA0000C301.pdf"
			(at 0 0 0)
			(layer "F.Fab")
			(hide yes)
			(effects
				(font
					(size 1.27 1.27)
					(thickness 0.15)
				)
			)
		)
		(property "Description" "SMD Chip Resistor, Jumper, 0 ohm, 100 mW, 0402 [1005 Metric], Thick Film, General Purpose"
			(at 0 0 0)
			(layer "F.Fab")
			(hide yes)
			(effects
				(font
					(size 1.27 1.27)
					(thickness 0.15)
				)
			)
		)
		(property "MPN" "ERJ2GE0R00X"
			(at 0 0 180)
			(unlocked yes)
			(layer "F.Fab")
			(hide yes)
			(effects
				(font
					(size 1 1)
					(thickness 0.15)
				)
			)
		)
		(property "Manufacturer" "Panasonic"
			(at 0 0 180)
			(unlocked yes)
			(layer "F.Fab")
			(hide yes)
			(effects
				(font
					(size 1 1)
					(thickness 0.15)
				)
			)
		)
		(property "License" "Apache-2.0"
			(at 0 0 180)
			(unlocked yes)
			(layer "F.Fab")
			(hide yes)
			(effects
				(font
					(size 1 1)
					(thickness 0.15)
				)
			)
		)
		(property "Author" "Antmicro"
			(at 0 0 180)
			(unlocked yes)
			(layer "F.Fab")
			(hide yes)
			(effects
				(font
					(size 1 1)
					(thickness 0.15)
				)
			)
		)
		(property "Val" "0R"
			(at 0 0 180)
			(unlocked yes)
			(layer "F.Fab")
			(hide yes)
			(effects
				(font
					(size 1 1)
					(thickness 0.15)
				)
			)
		)
		(property "Tolerance" "~"
			(at 0 0 180)
			(unlocked yes)
			(layer "F.Fab")
			(hide yes)
			(effects
				(font
					(size 1 1)
					(thickness 0.15)
				)
			)
		)
		(property "Current" "1A"
			(at 0 0 180)
			(unlocked yes)
			(layer "F.Fab")
			(hide yes)
			(effects
				(font
					(size 1 1)
					(thickness 0.15)
				)
			)
		)
		(sheetname "/Fan controller/")
		(sheetfile "fan-controller.kicad_sch")
		(attr smd exclude_from_pos_files exclude_from_bom dnp)
		(fp_rect
			(start -0.925 -0.47)
			(end 0.925 0.47)
			(stroke
				(width 0.05)
				(type default)
			)
			(fill no)
			(layer "F.CrtYd")
		)
		(fp_rect
			(start -0.5 -0.25)
			(end 0.5 0.25)
			(stroke
				(width 0.15)
				(type solid)
			)
			(fill no)
			(layer "F.Fab")
		)
		(pad "1" smd roundrect
			(at -0.48 0 180)
			(size 0.59 0.64)
			(layers "F.Cu" "F.Mask" "F.Paste")
			(roundrect_rratio 0.25)
			(net 389 "/Fan controller/V_{FAN}")
			(pintype "passive")
		)
		(pad "2" smd roundrect
			(at 0.48 0 180)
			(size 0.59 0.64)
			(layers "F.Cu" "F.Mask" "F.Paste")
			(roundrect_rratio 0.25)
			(net 314 "VCC")
			(pintype "passive")
		)
	)
	(footprint "antmicro-footprints:R_0402_1005Metric"
		(layer "F.Cu")
		(at 99.16 89.2145 180)
		(descr "Resistor SMD 0402")
		(tags "resistor SMD 0402")
		(property "Reference" "R101"
			(at -1.39 0.4645 0)
			(layer "F.SilkS")
			(effects
				(font
					(size 0.7 0.7)
					(thickness 0.15)
				)
				(justify right bottom)
			)
		)
		(property "Value" "R_0R_0402"
			(at -1.011843 1.772047 0)
			(layer "F.Fab")
			(hide yes)
			(effects
				(font
					(size 0.7 0.7)
					(thickness 0.15)
				)
				(justify right top)
			)
		)
		(property "Datasheet" "https://industrial.panasonic.com/cdbs/www-data/pdf/RDA0000/AOA0000C301.pdf"
			(at 0 0 0)
			(layer "F.Fab")
			(hide yes)
			(effects
				(font
					(size 1.27 1.27)
					(thickness 0.15)
				)
			)
		)
		(property "Description" "SMD Chip Resistor, Jumper, 0 ohm, 100 mW, 0402 [1005 Metric], Thick Film, General Purpose"
			(at 0 0 0)
			(layer "F.Fab")
			(hide yes)
			(effects
				(font
					(size 1.27 1.27)
					(thickness 0.15)
				)
			)
		)
		(property "MPN" "ERJ2GE0R00X"
			(at 0 0 180)
			(unlocked yes)
			(layer "F.Fab")
			(hide yes)
			(effects
				(font
					(size 1 1)
					(thickness 0.15)
				)
			)
		)
		(property "Manufacturer" "Panasonic"
			(at 0 0 180)
			(unlocked yes)
			(layer "F.Fab")
			(hide yes)
			(effects
				(font
					(size 1 1)
					(thickness 0.15)
				)
			)
		)
		(property "License" "Apache-2.0"
			(at 0 0 180)
			(unlocked yes)
			(layer "F.Fab")
			(hide yes)
			(effects
				(font
					(size 1 1)
					(thickness 0.15)
				)
			)
		)
		(property "Author" "Antmicro"
			(at 0 0 180)
			(unlocked yes)
			(layer "F.Fab")
			(hide yes)
			(effects
				(font
					(size 1 1)
					(thickness 0.15)
				)
			)
		)
		(property "Val" "0R"
			(at 0 0 180)
			(unlocked yes)
			(layer "F.Fab")
			(hide yes)
			(effects
				(font
					(size 1 1)
					(thickness 0.15)
				)
			)
		)
		(property "Tolerance" "~"
			(at 0 0 180)
			(unlocked yes)
			(layer "F.Fab")
			(hide yes)
			(effects
				(font
					(size 1 1)
					(thickness 0.15)
				)
			)
		)
		(property "Current" "1A"
			(at 0 0 180)
			(unlocked yes)
			(layer "F.Fab")
			(hide yes)
			(effects
				(font
					(size 1 1)
					(thickness 0.15)
				)
			)
		)
		(sheetname "/X710-AT2 PCIe/")
		(sheetfile "x710-at2-pcie.kicad_sch")
		(attr smd)
		(fp_rect
			(start -0.925 -0.47)
			(end 0.925 0.47)
			(stroke
				(width 0.05)
				(type default)
			)
			(fill no)
			(layer "F.CrtYd")
		)
		(fp_rect
			(start -0.5 -0.25)
			(end 0.5 0.25)
			(stroke
				(width 0.15)
				(type solid)
			)
			(fill no)
			(layer "F.Fab")
		)
		(pad "1" smd roundrect
			(at -0.48 0 180)
			(size 0.59 0.64)
			(layers "F.Cu" "F.Mask" "F.Paste")
			(roundrect_rratio 0.25)
			(net 45 "/OCuLink/REFCLK.-")
			(pintype "passive")
		)
		(pad "2" smd roundrect
			(at 0.48 0 180)
			(size 0.59 0.64)
			(layers "F.Cu" "F.Mask" "F.Paste")
			(roundrect_rratio 0.25)
			(net 403 "/X710-AT2 PCIe/CLK-")
			(pintype "passive")
		)
	)
	(footprint "antmicro-footprints:TP_SMD_0.75mm"
		(layer "F.Cu")
		(at 75.65 68.45)
		(property "Reference" "TP22"
			(at 0.45 -0.45 90)
			(layer "F.SilkS")
			(effects
				(font
					(size 0.7 0.7)
					(thickness 0.15)
				)
				(justify left bottom)
			)
		)
		(property "Value" "TP_0.75mm_SMD"
			(at 0 1.2 0)
			(layer "F.Fab")
			(hide yes)
			(effects
				(font
					(size 0.7 0.7)
					(thickness 0.15)
				)
				(justify left bottom)
			)
		)
		(property "Description" "SMT test point"
			(at 0 0 0)
			(layer "F.Fab")
			(hide yes)
			(effects
				(font
					(size 1.27 1.27)
					(thickness 0.15)
				)
			)
		)
		(property "MPN" ""
			(at 0 0 0)
			(unlocked yes)
			(layer "F.Fab")
			(hide yes)
			(effects
				(font
					(size 1 1)
					(thickness 0.15)
				)
			)
		)
		(property "Manufacturer" ""
			(at 0 0 0)
			(unlocked yes)
			(layer "F.Fab")
			(hide yes)
			(effects
				(font
					(size 1 1)
					(thickness 0.15)
				)
			)
		)
		(property "Author" "Antmicro"
			(at 0 0 0)
			(unlocked yes)
			(layer "F.Fab")
			(hide yes)
			(effects
				(font
					(size 1 1)
					(thickness 0.15)
				)
			)
		)
		(property "License" "Apache-2.0"
			(at 0 0 0)
			(unlocked yes)
			(layer "F.Fab")
			(hide yes)
			(effects
				(font
					(size 1 1)
					(thickness 0.15)
				)
			)
		)
		(sheetname "/Power/")
		(sheetfile "power.kicad_sch")
		(attr exclude_from_pos_files exclude_from_bom)
		(fp_circle
			(center 0 0)
			(end 0.475 0)
			(stroke
				(width 0.05)
				(type default)
			)
			(fill no)
			(layer "F.CrtYd")
		)
		(pad "1" smd circle
			(at 0 0)
			(size 0.75 0.75)
			(layers "F.Cu" "F.Mask")
			(net 314 "VCC")
			(pinfunction "1")
			(pintype "passive")
		)
	)
)
